# BASEBOARD_FAB2 (Tioga Pass) — schematic netlist excerpt (pin names and nets, part order shuffled) for the footprints in the layout excerpt that follows; sources: Cadence DE-HDL packaged netlist, KiCad conversion of Wiwynn_Tioga_Pass_MB.brd

TH7G1  MTG_KEYHOLE  EMPTY  pkg TH  page 195 : \1\ = GND
R6F9  RES  0.0 5% CHIP  pkg 0402  page 104 : A = CLK_156M_OSC_BRD_CPU0_DP ; B = CLK_156M_OSC_CPU0_HFI_DP
R9W36  RES  10.0K 1% CHIP  pkg 0402  page 139 : A = P3V3_STBY ; B = PU_DEV_OFF_N

(kicad_pcb
	(version 20260206)
	(generator "pcbnew")
	(generator_version "10.0")
	(general
		(thickness 1.6)
		(legacy_teardrops no)
	)
	(paper "A4")
	(title_block
		(title "Wiwynn_Tioga_Pass_MB.brd")
		(comment 1 "Tioga Pass / footprints 2151-2153 of 4770")
	)
	(layers
		(0 "F.Cu" signal "TOP")
		(4 "In1.Cu" signal "L2GND")
		(6 "In2.Cu" signal "L3")
		(8 "In3.Cu" signal "L4GND")
		(10 "In4.Cu" signal "L5")
		(12 "In5.Cu" signal "L6GND")
		(14 "In6.Cu" signal "L7VCC")
		(16 "In7.Cu" signal "L8VCC")
		(18 "In8.Cu" signal "L9GND")
		(20 "In9.Cu" signal "L10")
		(22 "In10.Cu" signal "L11GND")
		(24 "In11.Cu" signal "L12")
		(26 "In12.Cu" signal "L13GND")
		(2 "B.Cu" signal "BOTTOM")
		(9 "F.Adhes" user "F.Adhesive")
		(11 "B.Adhes" user "B.Adhesive")
		(13 "F.Paste" user "Package Geometry/Pastemask Top")
		(15 "B.Paste" user "Package Geometry/Pastemask Bottom")
		(5 "F.SilkS" user "Ref Des/Silkscreen Top")
		(7 "B.SilkS" user "Ref Des/Silkscreen Bottom")
		(1 "F.Mask" user "Board Geometry/Soldermask Top")
		(3 "B.Mask" user "Board Geometry/Soldermask Bottom")
		(17 "Dwgs.User" user "User.Drawings")
		(19 "Cmts.User" user "User.Comments")
		(21 "Eco1.User" user "User.Eco1")
		(23 "Eco2.User" user "User.Eco2")
		(25 "Edge.Cuts" user "Board Geometry/Outline")
		(27 "Margin" user)
		(31 "F.CrtYd" user "Package Geometry/Place Bound Top")
		(29 "B.CrtYd" user "Package Geometry/Place Bound Bottom")
		(35 "F.Fab" user "Ref Des/Assembly Top")
		(33 "B.Fab" user "Ref Des/Assembly Bottom")
	)
	(footprint ""
		(layer "F.Cu")
		(at 357.000048 1.999996 90)
		(property "Reference" "TH7G1"
			(at 3.624326 -3.051048 0)
			(unlocked yes)
			(layer "F.SilkS")
			(effects
				(font
					(size 0.7874 0.5842)
					(thickness 0.1524)
				)
				(justify left)
			)
		)
		(property "Value" ""
			(at 0 0 90)
			(layer "F.Fab")
			(effects
				(font
					(size 1.27 1.27)
				)
			)
		)
		(duplicate_pad_numbers_are_jumpers no)
		(fp_poly
			(pts
				(arc
					(start 3.0226 0.68834)
					(mid 3.042235 0.827855)
					(end 3.099562 0.956564)
				)
				(arc
					(start 3.099562 0.956564)
					(mid 4.012804 3.550073)
					(end 3.042158 6.12267)
				)
				(arc
					(start 3.042158 6.12267)
					(mid 0 7.518589)
					(end -3.042158 6.12267)
				)
				(arc
					(start -3.042158 6.12267)
					(mid -4.012854 3.55061)
					(end -3.100324 0.957326)
				)
				(arc
					(start -3.100324 0.957326)
					(mid -3.042498 0.827518)
					(end -3.0226 0.686816)
				)
				(arc
					(start -3.0226 -0.000254)
					(mid -2.137121 -2.137227)
					(end 0 -3.022346)
				)
				(arc
					(start 0 -3.022346)
					(mid 2.137227 -2.136973)
					(end 3.0226 0.000254)
				)
			)
			(stroke
				(width 0)
				(type default)
			)
			(fill no)
			(layer "F.CrtYd")
		)
		(pad "1" thru_hole custom
			(at 0 0 90)
			(size 2.00667 2.00667)
			(drill 0.3048)
			(layers "*.Cu" "*.Mask")
			(remove_unused_layers no)
			(net "GND")
			(clearance -0.889)
			(options
				(clearance outline)
				(anchor circle)
			)
			(primitives
				(gr_poly
					(pts
						(arc
							(start 3.042158 3.874516)
							(mid 0 5.270435)
							(end -3.042158 3.874516)
						)
						(arc
							(start -3.042158 3.874516)
							(mid -4.012854 1.302456)
							(end -3.100324 -1.290828)
						)
						(arc
							(start -3.100324 -1.290828)
							(mid -3.042498 -1.420636)
							(end -3.0226 -1.561338)
						)
						(arc
							(start -3.0226 -2.248408)
							(mid -2.137121 -4.385381)
							(end 0 -5.2705)
						)
						(arc
							(start 0 -5.2705)
							(mid 2.137227 -4.385127)
							(end 3.0226 -2.2479)
						)
						(arc
							(start 3.0226 -1.55956)
							(mid 3.04227 -1.420177)
							(end 3.099562 -1.29159)
						)
						(arc
							(start 3.099562 -1.29159)
							(mid 4.012804 1.301919)
							(end 3.042158 3.874516)
						)
					)
					(width 0)
					(fill yes)
				)
			)
		)
	)
	(footprint ""
		(layer "F.Cu")
		(at 482.03104 -51.36134)
		(property "Reference" "R9W36"
			(at -0.8382 -0.67818 0)
			(unlocked yes)
			(layer "F.SilkS")
			(effects
				(font
					(size 0.4064 0.254)
					(thickness 0.1524)
				)
				(justify left)
			)
		)
		(property "Value" ""
			(at 0 0 0)
			(layer "F.Fab")
			(effects
				(font
					(size 1.27 1.27)
				)
			)
		)
		(duplicate_pad_numbers_are_jumpers no)
		(fp_poly
			(pts
				(xy -0.2794 -0.1016) (xy 0.2794 -0.1016) (xy 0.2794 0.9906) (xy -0.2794 0.9906)
			)
			(stroke
				(width 0)
				(type default)
			)
			(fill no)
			(layer "F.CrtYd")
		)
		(fp_line
			(start -0.2794 -0.1016)
			(end -0.2794 0.9906)
			(stroke
				(width 0.1)
				(type default)
			)
			(layer "F.Fab")
		)
		(fp_line
			(start -0.2794 0.9906)
			(end 0.2794 0.9906)
			(stroke
				(width 0.1)
				(type default)
			)
			(layer "F.Fab")
		)
		(fp_line
			(start 0.2794 -0.1016)
			(end -0.2794 -0.1016)
			(stroke
				(width 0.1)
				(type default)
			)
			(layer "F.Fab")
		)
		(fp_line
			(start 0.2794 0.9906)
			(end 0.2794 -0.1016)
			(stroke
				(width 0.1)
				(type default)
			)
			(layer "F.Fab")
		)
		(pad "1" smd rect
			(at 0 0)
			(size 0.508 0.508)
			(layers "F.Cu" "F.Mask" "F.Paste")
			(net "P3V3_STBY")
		)
		(pad "2" smd rect
			(at 0 0.889)
			(size 0.508 0.508)
			(layers "F.Cu" "F.Mask" "F.Paste")
			(net "PU_DEV_OFF_N")
		)
		(zone
			(layer "F.Cu")
			(hatch none 0.5)
			(connect_pads
				(clearance 0)
			)
			(min_thickness 0.25)
			(keepout
				(tracks allowed)
				(vias not_allowed)
				(pads allowed)
				(copperpour not_allowed)
				(footprints allowed)
			)
			(placement
				(enabled no)
				(sheetname "")
			)
			(fill
				(thermal_gap 0.5)
				(thermal_bridge_width 0.5)
				(island_removal_mode 0)
			)
			(polygon
				(pts
					(xy 481.77704 -51.10734) (xy 482.28504 -51.10734) (xy 482.28504 -50.72634) (xy 481.77704 -50.72634)
				)
			)
		)
		(zone
			(layer "F.Cu")
			(hatch none 0.5)
			(connect_pads
				(clearance 0)
			)
			(min_thickness 0.25)
			(keepout
				(tracks not_allowed)
				(vias allowed)
				(pads allowed)
				(copperpour not_allowed)
				(footprints allowed)
			)
			(placement
				(enabled no)
				(sheetname "")
			)
			(fill
				(thermal_gap 0.5)
				(thermal_bridge_width 0.5)
				(island_removal_mode 0)
			)
			(polygon
				(pts
					(xy 481.77704 -50.72634) (xy 482.28504 -50.72634) (xy 482.28504 -51.10734) (xy 481.77704 -51.10734)
				)
			)
		)
	)
	(footprint ""
		(layer "F.Cu")
		(at 317.9826 -28.934918 90)
		(property "Reference" "R6F9"
			(at 0 0 90)
			(layer "F.SilkS")
			(hide yes)
			(effects
				(font
					(size 1.27 1.27)
				)
			)
		)
		(property "Value" ""
			(at 0 0 90)
			(layer "F.Fab")
			(effects
				(font
					(size 1.27 1.27)
				)
			)
		)
		(duplicate_pad_numbers_are_jumpers no)
		(fp_poly
			(pts
				(xy -0.2794 -0.1016) (xy 0.2794 -0.1016) (xy 0.2794 0.9906) (xy -0.2794 0.9906)
			)
			(stroke
				(width 0)
				(type default)
			)
			(fill no)
			(layer "F.CrtYd")
		)
		(fp_line
			(start 0.2794 -0.1016)
			(end -0.2794 -0.1016)
			(stroke
				(width 0.1)
				(type default)
			)
			(layer "F.Fab")
		)
		(fp_line
			(start -0.2794 -0.1016)
			(end -0.2794 0.9906)
			(stroke
				(width 0.1)
				(type default)
			)
			(layer "F.Fab")
		)
		(fp_line
			(start 0.2794 0.9906)
			(end 0.2794 -0.1016)
			(stroke
				(width 0.1)
				(type default)
			)
			(layer "F.Fab")
		)
		(fp_line
			(start -0.2794 0.9906)
			(end 0.2794 0.9906)
			(stroke
				(width 0.1)
				(type default)
			)
			(layer "F.Fab")
		)
		(pad "1" smd rect
			(at 0 0 90)
			(size 0.508 0.508)
			(layers "F.Cu" "F.Mask" "F.Paste")
			(net "CLK_156M_OSC_BRD_CPU0_DP")
		)
		(pad "2" smd rect
			(at 0 0.889 90)
			(size 0.508 0.508)
			(layers "F.Cu" "F.Mask" "F.Paste")
			(net "CLK_156M_OSC_CPU0_HFI_DP")
		)
		(zone
			(layer "F.Cu")
			(hatch none 0.5)
			(connect_pads
				(clearance 0)
			)
			(min_thickness 0.25)
			(keepout
				(tracks allowed)
				(vias not_allowed)
				(pads allowed)
				(copperpour not_allowed)
				(footprints allowed)
			)
			(placement
				(enabled no)
				(sheetname "")
			)
			(fill
				(thermal_gap 0.5)
				(thermal_bridge_width 0.5)
				(island_removal_mode 0)
			)
			(polygon
				(pts
					(xy 318.2366 -28.680918) (xy 318.2366 -29.188918) (xy 318.6176 -29.188918) (xy 318.6176 -28.680918)
				)
			)
		)
		(zone
			(layer "F.Cu")
			(hatch none 0.5)
			(connect_pads
				(clearance 0)
			)
			(min_thickness 0.25)
			(keepout
				(tracks not_allowed)
				(vias allowed)
				(pads allowed)
				(copperpour not_allowed)
				(footprints allowed)
			)
			(placement
				(enabled no)
				(sheetname "")
			)
			(fill
				(thermal_gap 0.5)
				(thermal_bridge_width 0.5)
				(island_removal_mode 0)
			)
			(polygon
				(pts
					(xy 318.6176 -28.680918) (xy 318.6176 -29.188918) (xy 318.2366 -29.188918) (xy 318.2366 -28.680918)
				)
			)
		)
	)
)
